(kicad_pcb
	(version 20260206)
	(generator "pcbnew")
	(generator_version "10.0")
	(general
		(thickness 1.6)
		(legacy_teardrops no)
	)
	(paper "A4")
	(title_block
		(title "03242023_DA0F0TMBIJ0_F0T_Motherboard_J_brd_V01_OCP.brd")
		(comment 1 "Grand Teton / footprint 1585 of 6105 (U4), pads 674-749 of 749")
	)
	(layers
		(0 "F.Cu" signal "TOP")
		(4 "In1.Cu" signal "GND")
		(6 "In2.Cu" signal "IN1")
		(8 "In3.Cu" signal "GND1")
		(10 "In4.Cu" signal "IN2")
		(12 "In5.Cu" signal "GND2")
		(14 "In6.Cu" signal "IN3")
		(16 "In7.Cu" signal "GND3")
		(18 "In8.Cu" signal "VCC")
		(20 "In9.Cu" signal "VCC1")
		(22 "In10.Cu" signal "GND4")
		(24 "In11.Cu" signal "IN4")
		(26 "In12.Cu" signal "GND5")
		(28 "In13.Cu" signal "IN5")
		(30 "In14.Cu" signal "GND6")
		(32 "In15.Cu" signal "IN6")
		(34 "In16.Cu" signal "GND7")
		(2 "B.Cu" signal "BOTTOM")
		(9 "F.Adhes" user "F.Adhesive")
		(11 "B.Adhes" user "B.Adhesive")
		(13 "F.Paste" user "Package Geometry/Pastemask Top")
		(15 "B.Paste" user "Package Geometry/Pastemask Bottom")
		(5 "F.SilkS" user "Ref Des/Silkscreen Top")
		(7 "B.SilkS" user "Ref Des/Silkscreen Bottom")
		(1 "F.Mask" user "Board Geometry/Soldermask Top")
		(3 "B.Mask" user "Board Geometry/Soldermask Bottom")
		(17 "Dwgs.User" user "User.Drawings")
		(19 "Cmts.User" user "User.Comments")
		(21 "Eco1.User" user "User.Eco1")
		(23 "Eco2.User" user "User.Eco2")
		(25 "Edge.Cuts" user "Board Geometry/Outline")
		(27 "Margin" user)
		(31 "F.CrtYd" user "Package Geometry/Place Bound Top")
		(29 "B.CrtYd" user "Package Geometry/Place Bound Bottom")
		(35 "F.Fab" user "Ref Des/Assembly Top")
		(33 "B.Fab" user "Ref Des/Assembly Bottom")
	)
	(footprint ""
		(layer "F.Cu")
		(at 336.899758 -48.450246)
		(property "Reference" "U4"
			(at -13.479018 -11.486896 0)
			(unlocked yes)
			(layer "F.SilkS")
			(effects
				(font
					(size 0.7874 0.5842)
					(thickness 0.1524)
				)
				(justify left)
			)
		)
		(property "Value" ""
			(at 0 0 0)
			(layer "F.Fab")
			(effects
				(font
					(size 1.27 1.27)
				)
			)
		)
		(duplicate_pad_numbers_are_jumpers no)
		(pad "R7" smd circle
			(at -7.733792 -4.2291 180)
			(size 0.381 0.381)
			(layers "F.Cu" "F.Mask" "F.Paste")
			(net "FM_PCH_BIOS_RCVR_MODE")
		)
		(pad "R10" smd circle
			(at -6.105398 -4.2291 180)
			(size 0.381 0.381)
			(layers "F.Cu" "F.Mask" "F.Paste")
			(net "FM_BOARD_SKU_ID3")
		)
		(pad "R13" smd circle
			(at -4.477512 -4.2291 180)
			(size 0.381 0.381)
			(layers "F.Cu" "F.Mask" "F.Paste")
			(net "GND")
		)
		(pad "R16" smd circle
			(at -2.849118 -4.2291 180)
			(size 0.381 0.381)
			(layers "F.Cu" "F.Mask" "F.Paste")
			(net "GND")
		)
		(pad "R20" smd circle
			(at -1.220978 -4.2291 180)
			(size 0.381 0.381)
			(layers "F.Cu" "F.Mask" "F.Paste")
			(net "GND")
		)
		(pad "R23" smd circle
			(at 0.406908 -4.2291 180)
			(size 0.381 0.381)
			(layers "F.Cu" "F.Mask" "F.Paste")
			(net "P1V05_PCH_PLL_AUX")
		)
		(pad "R26" smd circle
			(at 2.035302 -4.2291 180)
			(size 0.381 0.381)
			(layers "F.Cu" "F.Mask" "F.Paste")
			(net "P1V05_PCH_PLL_AUX")
		)
		(pad "R29" smd circle
			(at 3.663188 -4.2291 180)
			(size 0.381 0.381)
			(layers "F.Cu" "F.Mask" "F.Paste")
			(net "P1V05_PCH_PLL_AUX")
		)
		(pad "R32" smd circle
			(at 5.291582 -4.2291 180)
			(size 0.381 0.381)
			(layers "F.Cu" "F.Mask" "F.Paste")
			(net "TP_P3E_PCH_14_TX_DN")
		)
		(pad "R36" smd circle
			(at 6.919722 -4.2291 180)
			(size 0.381 0.381)
			(layers "F.Cu" "F.Mask" "F.Paste")
			(net "GND")
		)
		(pad "R40" smd circle
			(at 9.069832 -4.002024 180)
			(size 0.3048 0.3048)
			(layers "F.Cu" "F.Mask" "F.Paste")
			(net "USB3_PCH_RX_BUF_DN<4>")
		)
		(pad "R42" smd circle
			(at 9.899904 -4.002024 180)
			(size 0.3048 0.3048)
			(layers "F.Cu" "F.Mask" "F.Paste")
			(net "USB3_PCH_RX_BUF_DP<4>")
		)
		(pad "T8" smd circle
			(at -6.919722 -3.7592 180)
			(size 0.381 0.381)
			(layers "F.Cu" "F.Mask" "F.Paste")
			(net "PD_GPP_M_15")
		)
		(pad "T11" smd circle
			(at -5.291582 -3.7592 180)
			(size 0.381 0.381)
			(layers "F.Cu" "F.Mask" "F.Paste")
			(net "TP_PCH_GPP_N_1")
		)
		(pad "T15" smd circle
			(at -3.663188 -3.7592 180)
			(size 0.381 0.381)
			(layers "F.Cu" "F.Mask" "F.Paste")
			(net "P3V3_AUX")
		)
		(pad "T31" smd circle
			(at 4.477512 -3.7592 180)
			(size 0.381 0.381)
			(layers "F.Cu" "F.Mask" "F.Paste")
			(net "GND")
		)
		(pad "T34" smd circle
			(at 6.105398 -3.7592 180)
			(size 0.381 0.381)
			(layers "F.Cu" "F.Mask" "F.Paste")
			(net "TP_P3E_PCH_14_TX_DP")
		)
		(pad "T37" smd circle
			(at 7.733792 -3.7592 180)
			(size 0.381 0.381)
			(layers "F.Cu" "F.Mask" "F.Paste")
			(net "P3E_PCH_NVS_TX_DN<1>")
		)
		(pad "U1" smd oval
			(at -10.31494 -3.501644 270)
			(size 0.254 0.3302)
			(layers "F.Cu" "F.Mask" "F.Paste")
			(net "PD_GPP_I_16")
		)
		(pad "U3" smd circle
			(at -9.484868 -3.501644 180)
			(size 0.3048 0.3048)
			(layers "F.Cu" "F.Mask" "F.Paste")
			(net "FM_PCH_BMC_RST_R_N")
		)
		(pad "U5" smd circle
			(at -8.654796 -3.501644 180)
			(size 0.3048 0.3048)
			(layers "F.Cu" "F.Mask" "F.Paste")
			(net "GND")
		)
		(pad "U7" smd circle
			(at -7.733792 -3.2893 180)
			(size 0.381 0.381)
			(layers "F.Cu" "F.Mask" "F.Paste")
			(net "TP_GPP_M_12")
		)
		(pad "U10" smd circle
			(at -6.105398 -3.2893 180)
			(size 0.381 0.381)
			(layers "F.Cu" "F.Mask" "F.Paste")
			(net "GND")
		)
		(pad "U13" smd circle
			(at -4.477512 -3.2893 180)
			(size 0.381 0.381)
			(layers "F.Cu" "F.Mask" "F.Paste")
			(net "GND")
		)
		(pad "U17" smd circle
			(at -2.4003 -3.2004 180)
			(size 0.381 0.381)
			(layers "F.Cu" "F.Mask" "F.Paste")
			(net "P1V8_PCH_AUX")
		)
		(pad "U19" smd circle
			(at -1.6002 -3.2004 180)
			(size 0.381 0.381)
			(layers "F.Cu" "F.Mask" "F.Paste")
			(net "P1V8_PCH_AUX")
		)
		(pad "U20" smd circle
			(at -0.8001 -3.2004 180)
			(size 0.381 0.381)
			(layers "F.Cu" "F.Mask" "F.Paste")
			(net "P1V8_PCH_AUX")
		)
		(pad "U22" smd circle
			(at 0 -3.2004 180)
			(size 0.381 0.381)
			(layers "F.Cu" "F.Mask" "F.Paste")
			(net "P1V8_PCH_AUX")
		)
		(pad "U24" smd circle
			(at 0.8001 -3.2004 180)
			(size 0.381 0.381)
			(layers "F.Cu" "F.Mask" "F.Paste")
			(net "P1V8_PCH_AUX")
		)
		(pad "U25" smd circle
			(at 1.6002 -3.2004 180)
			(size 0.381 0.381)
			(layers "F.Cu" "F.Mask" "F.Paste")
			(net "GND")
		)
		(pad "U27" smd circle
			(at 2.4003 -3.2004 180)
			(size 0.381 0.381)
			(layers "F.Cu" "F.Mask" "F.Paste")
			(net "P1V05_PCH_PLL_AUX")
		)
		(pad "U29" smd circle
			(at 3.663188 -3.2893 180)
			(size 0.381 0.381)
			(layers "F.Cu" "F.Mask" "F.Paste")
			(net "P1V8_PCH_PLL_AUX")
		)
		(pad "U32" smd circle
			(at 5.291582 -3.2893 180)
			(size 0.381 0.381)
			(layers "F.Cu" "F.Mask" "F.Paste")
			(net "TP_P3E_PCH_13_TX_DN")
		)
		(pad "U36" smd circle
			(at 6.919722 -3.2893 180)
			(size 0.381 0.381)
			(layers "F.Cu" "F.Mask" "F.Paste")
			(net "TP_P3E_PCH_12_TX_DP")
		)
		(pad "U39" smd circle
			(at 8.654796 -3.501644 180)
			(size 0.3048 0.3048)
			(layers "F.Cu" "F.Mask" "F.Paste")
			(net "GND")
		)
		(pad "U41" smd circle
			(at 9.484868 -3.501644 180)
			(size 0.3048 0.3048)
			(layers "F.Cu" "F.Mask" "F.Paste")
			(net "P3E_PCH_BMC_RX_DN")
		)
		(pad "U43" smd oval
			(at 10.31494 -3.501644 270)
			(size 0.254 0.3302)
			(layers "F.Cu" "F.Mask" "F.Paste")
			(net "P3E_PCH_BMC_RX_DP")
		)
		(pad "V2" smd circle
			(at -9.899904 -3.001518 180)
			(size 0.3048 0.3048)
			(layers "F.Cu" "F.Mask" "F.Paste")
			(net "GND")
		)
		(pad "V4" smd circle
			(at -9.069832 -3.001518 180)
			(size 0.3048 0.3048)
			(layers "F.Cu" "F.Mask" "F.Paste")
			(net "PD_GPP_I_17")
		)
		(pad "V8" smd circle
			(at -6.919722 -2.8194 180)
			(size 0.381 0.381)
			(layers "F.Cu" "F.Mask" "F.Paste")
			(net "FM_BOARD_SKU_ID2")
		)
		(pad "V11" smd circle
			(at -5.291582 -2.8194 180)
			(size 0.381 0.381)
			(layers "F.Cu" "F.Mask" "F.Paste")
			(net "TP_PCH_GPP_N_4")
		)
		(pad "V15" smd circle
			(at -3.663188 -2.8194 180)
			(size 0.381 0.381)
			(layers "F.Cu" "F.Mask" "F.Paste")
			(net "P3V3_AUX")
		)
		(pad "V31" smd circle
			(at 4.477512 -2.8194 180)
			(size 0.381 0.381)
			(layers "F.Cu" "F.Mask" "F.Paste")
			(net "GND")
		)
		(pad "V34" smd circle
			(at 6.105398 -2.8194 180)
			(size 0.381 0.381)
			(layers "F.Cu" "F.Mask" "F.Paste")
			(net "TP_P3E_PCH_12_TX_DN")
		)
		(pad "V37" smd circle
			(at 7.733792 -2.8194 180)
			(size 0.381 0.381)
			(layers "F.Cu" "F.Mask" "F.Paste")
			(net "P3E_PCH_NVS_TX_DP<1>")
		)
		(pad "V40" smd circle
			(at 9.069832 -3.001518 180)
			(size 0.3048 0.3048)
			(layers "F.Cu" "F.Mask" "F.Paste")
			(net "P3E_PCH_E1S_RX_DN<3>")
		)
		(pad "V42" smd circle
			(at 9.899904 -3.001518 180)
			(size 0.3048 0.3048)
			(layers "F.Cu" "F.Mask" "F.Paste")
			(net "P3E_PCH_E1S_RX_DP<3>")
		)
		(pad "W1" smd oval
			(at -10.31494 -2.501138 270)
			(size 0.254 0.3302)
			(layers "F.Cu" "F.Mask" "F.Paste")
			(net "FM_PCH_BOOT_BIOS_STRAP")
		)
		(pad "W3" smd circle
			(at -9.484868 -2.501138 180)
			(size 0.3048 0.3048)
			(layers "F.Cu" "F.Mask" "F.Paste")
			(net "GND")
		)
		(pad "W5" smd circle
			(at -8.654796 -2.501138 180)
			(size 0.3048 0.3048)
			(layers "F.Cu" "F.Mask" "F.Paste")
			(net "GND")
		)
		(pad "W7" smd circle
			(at -7.733792 -2.3495 180)
			(size 0.381 0.381)
			(layers "F.Cu" "F.Mask" "F.Paste")
			(net "FM_BOARD_SKU_ID1")
		)
		(pad "W10" smd circle
			(at -6.105398 -2.3495 180)
			(size 0.381 0.381)
			(layers "F.Cu" "F.Mask" "F.Paste")
			(net "PD_GPP_M_8")
		)
		(pad "W13" smd circle
			(at -4.477512 -2.3495 180)
			(size 0.381 0.381)
			(layers "F.Cu" "F.Mask" "F.Paste")
			(net "PD_GPP_M_17")
		)
		(pad "W17" smd circle
			(at -2.4003 -2.4003 180)
			(size 0.381 0.381)
			(layers "F.Cu" "F.Mask" "F.Paste")
			(net "P1V05_PCH_AUX")
		)
		(pad "W19" smd circle
			(at -1.6002 -2.4003 180)
			(size 0.381 0.381)
			(layers "F.Cu" "F.Mask" "F.Paste")
			(net "P1V05_PCH_AUX")
		)
		(pad "W20" smd circle
			(at -0.8001 -2.4003 180)
			(size 0.381 0.381)
			(layers "F.Cu" "F.Mask" "F.Paste")
			(net "P1V05_PCH_AUX")
		)
		(pad "W22" smd circle
			(at 0 -2.4003 180)
			(size 0.381 0.381)
			(layers "F.Cu" "F.Mask" "F.Paste")
			(net "P1V05_PCH_AUX")
		)
		(pad "W24" smd circle
			(at 0.8001 -2.4003 180)
			(size 0.381 0.381)
			(layers "F.Cu" "F.Mask" "F.Paste")
			(net "P1V05_PCH_AUX")
		)
		(pad "W25" smd circle
			(at 1.6002 -2.4003 180)
			(size 0.381 0.381)
			(layers "F.Cu" "F.Mask" "F.Paste")
			(net "GND")
		)
		(pad "W27" smd circle
			(at 2.4003 -2.4003 180)
			(size 0.381 0.381)
			(layers "F.Cu" "F.Mask" "F.Paste")
			(net "P1V8_PCH_PLL_AUX")
		)
		(pad "W29" smd circle
			(at 3.663188 -2.3495 180)
			(size 0.381 0.381)
			(layers "F.Cu" "F.Mask" "F.Paste")
			(net "P1V8_PCH_PLL_AUX")
		)
		(pad "W32" smd circle
			(at 5.291582 -2.3495 180)
			(size 0.381 0.381)
			(layers "F.Cu" "F.Mask" "F.Paste")
			(net "TP_P3E_PCH_13_TX_DP")
		)
		(pad "W36" smd circle
			(at 6.919722 -2.3495 180)
			(size 0.381 0.381)
			(layers "F.Cu" "F.Mask" "F.Paste")
			(net "P3E_PCH_NVS_TX_DN<0>")
		)
		(pad "W39" smd circle
			(at 8.654796 -2.501138 180)
			(size 0.3048 0.3048)
			(layers "F.Cu" "F.Mask" "F.Paste")
			(net "GND")
		)
		(pad "W41" smd circle
			(at 9.484868 -2.501138 180)
			(size 0.3048 0.3048)
			(layers "F.Cu" "F.Mask" "F.Paste")
			(net "P3E_PCH_E1S_RX_DN<2>")
		)
		(pad "W43" smd oval
			(at 10.31494 -2.501138 270)
			(size 0.254 0.3302)
			(layers "F.Cu" "F.Mask" "F.Paste")
			(net "P3E_PCH_E1S_RX_DP<2>")
		)
		(pad "Y2" smd circle
			(at -9.899904 -2.001012 180)
			(size 0.3048 0.3048)
			(layers "F.Cu" "F.Mask" "F.Paste")
			(net "FM_PLT_BMC_THERMTRIP_R_N")
		)
		(pad "Y4" smd circle
			(at -9.069832 -2.001012 180)
			(size 0.3048 0.3048)
			(layers "F.Cu" "F.Mask" "F.Paste")
			(net "FM_BIOS_IMAGE_SWAP_N")
		)
		(pad "Y8" smd circle
			(at -6.919722 -1.8796 180)
			(size 0.381 0.381)
			(layers "F.Cu" "F.Mask" "F.Paste")
			(net "GND")
		)
		(pad "Y11" smd circle
			(at -5.291582 -1.8796 180)
			(size 0.381 0.381)
			(layers "F.Cu" "F.Mask" "F.Paste")
			(net "GND")
		)
		(pad "Y15" smd circle
			(at -3.663188 -1.8796 180)
			(size 0.381 0.381)
			(layers "F.Cu" "F.Mask" "F.Paste")
			(net "GND")
		)
		(pad "Y31" smd circle
			(at 4.477512 -1.8796 180)
			(size 0.381 0.381)
			(layers "F.Cu" "F.Mask" "F.Paste")
			(net "GND")
		)
		(pad "Y34" smd circle
			(at 6.105398 -1.8796 180)
			(size 0.381 0.381)
			(layers "F.Cu" "F.Mask" "F.Paste")
			(net "GND")
		)
		(pad "Y37" smd circle
			(at 7.733792 -1.8796 180)
			(size 0.381 0.381)
			(layers "F.Cu" "F.Mask" "F.Paste")
			(net "P3E_PCH_NVS_TX_DP<0>")
		)
		(pad "Y40" smd circle
			(at 9.069832 -2.001012 180)
			(size 0.3048 0.3048)
			(layers "F.Cu" "F.Mask" "F.Paste")
			(net "P3E_PCH_E1S_RX_DN<1>")
		)
		(pad "Y42" smd circle
			(at 9.899904 -2.001012 180)
			(size 0.3048 0.3048)
			(layers "F.Cu" "F.Mask" "F.Paste")
			(net "P3E_PCH_E1S_RX_DP<1>")
		)
	)
)
